# BASEBOARD_FAB2 (Tioga Pass) — schematic netlist excerpt (pin names and nets, part order shuffled) for the footprints in the layout excerpt that follows; sources: Cadence DE-HDL packaged netlist, KiCad conversion of Wiwynn_Tioga_Pass_MB.brd

C1D36  CAP  0.220UF 16V 10% X7R  pkg 0402  page 207 : A = VR_PVCCIN_CPU1_PH2_BOOT ; B = VR_PVCCIN_CPU1_PH2_PHASE
CR1F3  DIODE  SDMK0340L IC  pkg SM  page 181 : C = FM_MATED_IN_D2_N ; A = FM_MATED_IN_D1_N
R1E10  RES  1.00K 1% CHIP  pkg 0402  page 167 : A = P3V3_STBY ; B = PD_TMP421_2_A1

(kicad_pcb
	(version 20260206)
	(generator "pcbnew")
	(generator_version "10.0")
	(general
		(thickness 1.6)
		(legacy_teardrops no)
	)
	(paper "A4")
	(title_block
		(title "Wiwynn_Tioga_Pass_MB.brd")
		(comment 1 "Tioga Pass / footprints 807-809 of 4770")
	)
	(layers
		(0 "F.Cu" signal "TOP")
		(4 "In1.Cu" signal "L2GND")
		(6 "In2.Cu" signal "L3")
		(8 "In3.Cu" signal "L4GND")
		(10 "In4.Cu" signal "L5")
		(12 "In5.Cu" signal "L6GND")
		(14 "In6.Cu" signal "L7VCC")
		(16 "In7.Cu" signal "L8VCC")
		(18 "In8.Cu" signal "L9GND")
		(20 "In9.Cu" signal "L10")
		(22 "In10.Cu" signal "L11GND")
		(24 "In11.Cu" signal "L12")
		(26 "In12.Cu" signal "L13GND")
		(2 "B.Cu" signal "BOTTOM")
		(9 "F.Adhes" user "F.Adhesive")
		(11 "B.Adhes" user "B.Adhesive")
		(13 "F.Paste" user "Package Geometry/Pastemask Top")
		(15 "B.Paste" user "Package Geometry/Pastemask Bottom")
		(5 "F.SilkS" user "Ref Des/Silkscreen Top")
		(7 "B.SilkS" user "Ref Des/Silkscreen Bottom")
		(1 "F.Mask" user "Board Geometry/Soldermask Top")
		(3 "B.Mask" user "Board Geometry/Soldermask Bottom")
		(17 "Dwgs.User" user "User.Drawings")
		(19 "Cmts.User" user "User.Comments")
		(21 "Eco1.User" user "User.Eco1")
		(23 "Eco2.User" user "User.Eco2")
		(25 "Edge.Cuts" user "Board Geometry/Outline")
		(27 "Margin" user)
		(31 "F.CrtYd" user "Package Geometry/Place Bound Top")
		(29 "B.CrtYd" user "Package Geometry/Place Bound Bottom")
		(35 "F.Fab" user "Ref Des/Assembly Top")
		(33 "B.Fab" user "Ref Des/Assembly Bottom")
	)
	(footprint ""
		(layer "F.Cu")
		(at 2.032 -69.088 180)
		(property "Reference" "R1E10"
			(at 0 0 180)
			(layer "F.SilkS")
			(hide yes)
			(effects
				(font
					(size 1.27 1.27)
				)
			)
		)
		(property "Value" ""
			(at 0 0 180)
			(layer "F.Fab")
			(effects
				(font
					(size 1.27 1.27)
				)
			)
		)
		(duplicate_pad_numbers_are_jumpers no)
		(fp_poly
			(pts
				(xy -0.2794 -0.1016) (xy 0.2794 -0.1016) (xy 0.2794 0.9906) (xy -0.2794 0.9906)
			)
			(stroke
				(width 0)
				(type default)
			)
			(fill no)
			(layer "F.CrtYd")
		)
		(fp_line
			(start 0.2794 0.9906)
			(end 0.2794 -0.1016)
			(stroke
				(width 0.1)
				(type default)
			)
			(layer "F.Fab")
		)
		(fp_line
			(start 0.2794 -0.1016)
			(end -0.2794 -0.1016)
			(stroke
				(width 0.1)
				(type default)
			)
			(layer "F.Fab")
		)
		(fp_line
			(start -0.2794 0.9906)
			(end 0.2794 0.9906)
			(stroke
				(width 0.1)
				(type default)
			)
			(layer "F.Fab")
		)
		(fp_line
			(start -0.2794 -0.1016)
			(end -0.2794 0.9906)
			(stroke
				(width 0.1)
				(type default)
			)
			(layer "F.Fab")
		)
		(pad "1" smd rect
			(at 0 0 180)
			(size 0.508 0.508)
			(layers "F.Cu" "F.Mask" "F.Paste")
			(net "P3V3_STBY")
		)
		(pad "2" smd rect
			(at 0 0.889 180)
			(size 0.508 0.508)
			(layers "F.Cu" "F.Mask" "F.Paste")
			(net "PD_TMP421_2_A1")
		)
		(zone
			(layer "F.Cu")
			(hatch none 0.5)
			(connect_pads
				(clearance 0)
			)
			(min_thickness 0.25)
			(keepout
				(tracks not_allowed)
				(vias allowed)
				(pads allowed)
				(copperpour not_allowed)
				(footprints allowed)
			)
			(placement
				(enabled no)
				(sheetname "")
			)
			(fill
				(thermal_gap 0.5)
				(thermal_bridge_width 0.5)
				(island_removal_mode 0)
			)
			(polygon
				(pts
					(xy 2.286 -69.723) (xy 1.778 -69.723) (xy 1.778 -69.342) (xy 2.286 -69.342)
				)
			)
		)
		(zone
			(layer "F.Cu")
			(hatch none 0.5)
			(connect_pads
				(clearance 0)
			)
			(min_thickness 0.25)
			(keepout
				(tracks allowed)
				(vias not_allowed)
				(pads allowed)
				(copperpour not_allowed)
				(footprints allowed)
			)
			(placement
				(enabled no)
				(sheetname "")
			)
			(fill
				(thermal_gap 0.5)
				(thermal_bridge_width 0.5)
				(island_removal_mode 0)
			)
			(polygon
				(pts
					(xy 2.286 -69.342) (xy 1.778 -69.342) (xy 1.778 -69.723) (xy 2.286 -69.723)
				)
			)
		)
	)
	(footprint ""
		(layer "F.Cu")
		(at 28.829 -66.929 90)
		(property "Reference" "C1D36"
			(at 0 0 90)
			(layer "F.SilkS")
			(hide yes)
			(effects
				(font
					(size 1.27 1.27)
				)
			)
		)
		(property "Value" ""
			(at 0 0 90)
			(layer "F.Fab")
			(effects
				(font
					(size 1.27 1.27)
				)
			)
		)
		(duplicate_pad_numbers_are_jumpers no)
		(fp_rect
			(start -0.3048 0.9906)
			(end 0.3048 -0.1016)
			(stroke
				(width 0)
				(type default)
			)
			(fill no)
			(layer "F.CrtYd")
		)
		(fp_line
			(start 0.3048 -0.1016)
			(end -0.3048 -0.1016)
			(stroke
				(width 0.1)
				(type default)
			)
			(layer "F.Fab")
		)
		(fp_line
			(start -0.3048 -0.1016)
			(end -0.3048 0.9906)
			(stroke
				(width 0.1)
				(type default)
			)
			(layer "F.Fab")
		)
		(fp_line
			(start 0.3048 0.9906)
			(end 0.3048 -0.1016)
			(stroke
				(width 0.1)
				(type default)
			)
			(layer "F.Fab")
		)
		(fp_line
			(start -0.3048 0.9906)
			(end 0.3048 0.9906)
			(stroke
				(width 0.1)
				(type default)
			)
			(layer "F.Fab")
		)
		(pad "1" smd rect
			(at 0 0 90)
			(size 0.508 0.508)
			(layers "F.Cu" "F.Mask" "F.Paste")
			(net "VR_PVCCIN_CPU1_PH2_BOOT")
		)
		(pad "2" smd rect
			(at 0 0.889 90)
			(size 0.508 0.508)
			(layers "F.Cu" "F.Mask" "F.Paste")
			(net "VR_PVCCIN_CPU1_PH2_PHASE")
		)
		(zone
			(layer "F.Cu")
			(hatch none 0.5)
			(connect_pads
				(clearance 0)
			)
			(min_thickness 0.25)
			(keepout
				(tracks allowed)
				(vias not_allowed)
				(pads allowed)
				(copperpour not_allowed)
				(footprints allowed)
			)
			(placement
				(enabled no)
				(sheetname "")
			)
			(fill
				(thermal_gap 0.5)
				(thermal_bridge_width 0.5)
				(island_removal_mode 0)
			)
			(polygon
				(pts
					(xy 29.464 -66.675) (xy 29.464 -67.183) (xy 29.083 -67.183) (xy 29.083 -66.675)
				)
			)
		)
		(zone
			(layer "F.Cu")
			(hatch none 0.5)
			(connect_pads
				(clearance 0)
			)
			(min_thickness 0.25)
			(keepout
				(tracks not_allowed)
				(vias allowed)
				(pads allowed)
				(copperpour not_allowed)
				(footprints allowed)
			)
			(placement
				(enabled no)
				(sheetname "")
			)
			(fill
				(thermal_gap 0.5)
				(thermal_bridge_width 0.5)
				(island_removal_mode 0)
			)
			(polygon
				(pts
					(xy 29.464 -66.675) (xy 29.464 -67.183) (xy 29.083 -67.183) (xy 29.083 -66.675)
				)
			)
		)
	)
	(footprint ""
		(layer "F.Cu")
		(at 20.701 -32.258)
		(property "Reference" "CR1F3"
			(at -3.429 -1.24333 0)
			(unlocked yes)
			(layer "F.SilkS")
			(effects
				(font
					(size 0.7874 0.5842)
					(thickness 0.1524)
				)
				(justify left)
			)
		)
		(property "Value" ""
			(at 0 0 0)
			(layer "F.Fab")
			(effects
				(font
					(size 1.27 1.27)
				)
			)
		)
		(duplicate_pad_numbers_are_jumpers no)
		(fp_line
			(start -1.8161 1.664462)
			(end -1.335278 0.831596)
			(stroke
				(width 0.1524)
				(type default)
			)
			(layer "F.SilkS")
		)
		(fp_line
			(start -1.335278 -0.291846)
			(end -1.335278 0.831596)
			(stroke
				(width 0.1524)
				(type default)
			)
			(layer "F.SilkS")
		)
		(fp_line
			(start -1.335278 0.831596)
			(end -0.854456 1.664462)
			(stroke
				(width 0.1524)
				(type default)
			)
			(layer "F.SilkS")
		)
		(fp_line
			(start -1.335278 1.664462)
			(end -1.8161 1.664462)
			(stroke
				(width 0.1524)
				(type default)
			)
			(layer "F.SilkS")
		)
		(fp_line
			(start -1.335278 2.576068)
			(end -1.335278 1.664462)
			(stroke
				(width 0.1524)
				(type default)
			)
			(layer "F.SilkS")
		)
		(fp_line
			(start -0.854456 0.831596)
			(end -1.8161 0.831596)
			(stroke
				(width 0.1524)
				(type default)
			)
			(layer "F.SilkS")
		)
		(fp_line
			(start -0.854456 1.664462)
			(end -1.335278 1.664462)
			(stroke
				(width 0.1524)
				(type default)
			)
			(layer "F.SilkS")
		)
		(fp_rect
			(start -0.67437 2.04216)
			(end 0.67437 0.24384)
			(stroke
				(width 0)
				(type default)
			)
			(fill no)
			(layer "F.CrtYd")
		)
		(fp_line
			(start -1.8161 1.664462)
			(end -1.335278 0.831596)
			(stroke
				(width 0.1)
				(type default)
			)
			(layer "F.Fab")
		)
		(fp_line
			(start -1.335278 0.831596)
			(end -1.335278 -0.291846)
			(stroke
				(width 0.1)
				(type default)
			)
			(layer "F.Fab")
		)
		(fp_line
			(start -1.335278 0.831596)
			(end -0.854456 1.664462)
			(stroke
				(width 0.1)
				(type default)
			)
			(layer "F.Fab")
		)
		(fp_line
			(start -1.335278 1.664462)
			(end -1.335278 2.576068)
			(stroke
				(width 0.1)
				(type default)
			)
			(layer "F.Fab")
		)
		(fp_line
			(start -0.854456 0.831596)
			(end -1.8161 0.831596)
			(stroke
				(width 0.1)
				(type default)
			)
			(layer "F.Fab")
		)
		(fp_line
			(start -0.854456 1.664462)
			(end -1.8161 1.664462)
			(stroke
				(width 0.1)
				(type default)
			)
			(layer "F.Fab")
		)
		(fp_line
			(start -0.67437 0.24384)
			(end -0.67437 2.04216)
			(stroke
				(width 0.1)
				(type default)
			)
			(layer "F.Fab")
		)
		(fp_line
			(start -0.67437 2.04216)
			(end 0.67437 2.04216)
			(stroke
				(width 0.1)
				(type default)
			)
			(layer "F.Fab")
		)
		(fp_line
			(start 0.67437 0.24384)
			(end -0.67437 0.24384)
			(stroke
				(width 0.1)
				(type default)
			)
			(layer "F.Fab")
		)
		(fp_line
			(start 0.67437 2.04216)
			(end 0.67437 0.24384)
			(stroke
				(width 0.1)
				(type default)
			)
			(layer "F.Fab")
		)
		(pad "1" smd rect
			(at 0 0)
			(size 0.4064 1.016)
			(layers "F.Cu" "F.Mask" "F.Paste")
			(net "FM_MATED_IN_D2_N")
		)
		(pad "2" smd rect
			(at 0 2.286)
			(size 0.4064 1.016)
			(layers "F.Cu" "F.Mask" "F.Paste")
			(net "FM_MATED_IN_D1_N")
		)
	)
)
